FILE_TYPE = MACRO_DRAWING;
SET COLOR_WIRE YELLOW;
SET COLOR_PROP ORANGE;
SET COLOR_DOT WHITE;
SET COLOR_ARC YELLOW;
SET COLOR_BODY GREEN;
SET COLOR_NOTE PURPLE;
SET PROP_DISPLAY VALUE;
SET PAGE_NUMBER P50;
FORCEADD OFFPAGE..1
(-1025 2100);
FORCEPROP 2 LAST $XR0 126 
J 0
(-1277 2100);
DISPLAY 0.638298 (-1277 2100);
PAINT MONO (-1277 2100);
FORCEPROP 2 LAST CDS_LIB standard
J 0
(-1025 2100);
PAINT MONO (-1025 2100);
DISPLAY INVISIBLE (-1025 2100);
FORCEPROP 1 LAST OFFPAGE TRUE
J 0
(-700 1975);
DISPLAY 0.872340 (-700 1975);
DISPLAY INVISIBLE (-700 1975);
FORCEPROP 1 LAST COMMENT_BODY TRUE
J 0
(-900 2000);
DISPLAY 0.872340 (-900 2000);
PAINT GREEN (-900 2000);
DISPLAY INVISIBLE (-900 2000);
FORCEPROP 2 LAST PATH I19
J 0
(-975 2175);
DISPLAY 1.021277 (-975 2175);
DISPLAY INVISIBLE (-975 2175);
FORCEADD OFFPAGE..1
(-1025 2150);
FORCEPROP 2 LAST $XR0 126 
J 0
(-1277 2150);
DISPLAY 0.638298 (-1277 2150);
PAINT MONO (-1277 2150);
FORCEPROP 2 LAST CDS_LIB standard
J 0
(-1025 2150);
PAINT MONO (-1025 2150);
DISPLAY INVISIBLE (-1025 2150);
FORCEPROP 1 LAST OFFPAGE TRUE
J 0
(-700 2025);
DISPLAY 0.872340 (-700 2025);
DISPLAY INVISIBLE (-700 2025);
FORCEPROP 1 LAST COMMENT_BODY TRUE
J 0
(-900 2050);
DISPLAY 0.872340 (-900 2050);
PAINT GREEN (-900 2050);
DISPLAY INVISIBLE (-900 2050);
FORCEPROP 2 LAST PATH I20
J 0
(-975 2225);
DISPLAY 1.021277 (-975 2225);
DISPLAY INVISIBLE (-975 2225);
FORCEADD OFFPAGE..1
(-1025 2200);
FORCEPROP 2 LAST $XR0 126 
J 0
(-1277 2200);
DISPLAY 0.638298 (-1277 2200);
PAINT MONO (-1277 2200);
FORCEPROP 2 LAST CDS_LIB standard
J 0
(-1025 2200);
PAINT MONO (-1025 2200);
DISPLAY INVISIBLE (-1025 2200);
FORCEPROP 1 LAST OFFPAGE TRUE
J 0
(-700 2075);
DISPLAY 0.872340 (-700 2075);
DISPLAY INVISIBLE (-700 2075);
FORCEPROP 1 LAST COMMENT_BODY TRUE
J 0
(-900 2100);
DISPLAY 0.872340 (-900 2100);
PAINT GREEN (-900 2100);
DISPLAY INVISIBLE (-900 2100);
FORCEPROP 2 LAST PATH I21
J 0
(-975 2275);
DISPLAY 1.021277 (-975 2275);
DISPLAY INVISIBLE (-975 2275);
FORCEADD OFFPAGE..1
(-1025 2250);
FORCEPROP 2 LAST $XR0 126 
J 0
(-1277 2250);
DISPLAY 0.638298 (-1277 2250);
PAINT MONO (-1277 2250);
FORCEPROP 2 LAST CDS_LIB standard
J 0
(-1025 2250);
PAINT MONO (-1025 2250);
DISPLAY INVISIBLE (-1025 2250);
FORCEPROP 1 LAST OFFPAGE TRUE
J 0
(-700 2125);
DISPLAY 0.872340 (-700 2125);
DISPLAY INVISIBLE (-700 2125);
FORCEPROP 1 LAST COMMENT_BODY TRUE
J 0
(-900 2150);
DISPLAY 0.872340 (-900 2150);
PAINT GREEN (-900 2150);
DISPLAY INVISIBLE (-900 2150);
FORCEPROP 2 LAST PATH I22
J 0
(-975 2325);
DISPLAY 1.021277 (-975 2325);
DISPLAY INVISIBLE (-975 2325);
FORCEADD SOCKET4677_AZIF0045P001C01CS..7
(1900 2175);
FORCEPROP 1 LAST PART_NUMBER DGA^7000023
J 0
(850 3525);
DISPLAY 0.723404 (850 3525);
PAINT GREEN (850 3525);
DISPLAY INVISIBLE (850 3525);
FORCEPROP 2 LAST PART_TYPE SMLF
J 0
(850 3700);
DISPLAY 1.021277 (850 3700);
FORCEPROP 1 LAST MATERIAL IO
J 0
(850 3450);
DISPLAY 0.723404 (850 3450);
PAINT GREEN (850 3450);
FORCEPROP 2 LAST VALUE SOCKET4677_AZIF0045-P001C01CS
J 0
(850 3650);
DISPLAY 1.021277 (850 3650);
FORCEPROP 1 LAST $LOCATION U1
J 0
(850 3600);
DISPLAY 0.723404 (850 3600);
PAINT GREEN (850 3600);
FORCEPROP 0 LASTPIN (700 1950) $PN CC29
J 2
(690 1960);
DISPLAY 0.680851 (690 1960);
PAINT MONO (690 1960);
FORCEPROP 0 LASTPIN (700 1150) $PN CB30
J 2
(690 1160);
DISPLAY 0.680851 (690 1160);
PAINT MONO (690 1160);
FORCEPROP 0 LASTPIN (700 1100) $PN BY28
J 2
(690 1110);
DISPLAY 0.680851 (690 1110);
PAINT MONO (690 1110);
FORCEPROP 0 LASTPIN (700 1900) $PN CD28
J 2
(690 1910);
DISPLAY 0.680851 (690 1910);
PAINT MONO (690 1910);
FORCEPROP 0 LASTPIN (3100 1150) $PN BF67
J 0
(3110 1160);
DISPLAY 0.680851 (3110 1160);
PAINT MONO (3110 1160);
FORCEPROP 0 LASTPIN (3100 1100) $PN BK67
J 0
(3110 1110);
DISPLAY 0.680851 (3110 1110);
PAINT MONO (3110 1110);
FORCEPROP 0 LASTPIN (700 1850) $PN CC27
J 2
(690 1860);
DISPLAY 0.680851 (690 1860);
PAINT MONO (690 1860);
FORCEPROP 0 LASTPIN (700 1800) $PN BY30
J 2
(690 1810);
DISPLAY 0.680851 (690 1810);
PAINT MONO (690 1810);
FORCEPROP 0 LASTPIN (700 1750) $PN CA29
J 2
(690 1760);
DISPLAY 0.680851 (690 1760);
PAINT MONO (690 1760);
FORCEPROP 0 LASTPIN (700 1700) $PN BV30
J 2
(690 1710);
DISPLAY 0.680851 (690 1710);
PAINT MONO (690 1710);
FORCEPROP 0 LASTPIN (700 1650) $PN CA27
J 2
(690 1660);
DISPLAY 0.680851 (690 1660);
PAINT MONO (690 1660);
FORCEPROP 0 LASTPIN (700 1600) $PN BV28
J 2
(690 1610);
DISPLAY 0.680851 (690 1610);
PAINT MONO (690 1610);
FORCEPROP 0 LASTPIN (700 1550) $PN BU27
J 2
(690 1560);
DISPLAY 0.680851 (690 1560);
PAINT MONO (690 1560);
FORCEPROP 0 LASTPIN (700 1500) $PN BT28
J 2
(690 1510);
DISPLAY 0.680851 (690 1510);
PAINT MONO (690 1510);
FORCEPROP 0 LASTPIN (700 1450) $PN BU29
J 2
(690 1460);
DISPLAY 0.680851 (690 1460);
PAINT MONO (690 1460);
FORCEPROP 0 LASTPIN (3100 1950) $PN BC70
J 0
(3110 1960);
DISPLAY 0.680851 (3110 1960);
PAINT MONO (3110 1960);
FORCEPROP 0 LASTPIN (700 1400) $PN BT30
J 2
(690 1410);
DISPLAY 0.680851 (690 1410);
PAINT MONO (690 1410);
FORCEPROP 0 LASTPIN (3100 1900) $PN BE70
J 0
(3110 1910);
DISPLAY 0.680851 (3110 1910);
PAINT MONO (3110 1910);
FORCEPROP 0 LASTPIN (700 1350) $PN BN27
J 2
(690 1360);
DISPLAY 0.680851 (690 1360);
PAINT MONO (690 1360);
FORCEPROP 0 LASTPIN (3100 1850) $PN BD69
J 0
(3110 1860);
DISPLAY 0.680851 (3110 1860);
PAINT MONO (3110 1860);
FORCEPROP 0 LASTPIN (700 1300) $PN BP28
J 2
(690 1310);
DISPLAY 0.680851 (690 1310);
PAINT MONO (690 1310);
FORCEPROP 0 LASTPIN (3100 1800) $PN BF69
J 0
(3110 1810);
DISPLAY 0.680851 (3110 1810);
PAINT MONO (3110 1810);
FORCEPROP 0 LASTPIN (700 1250) $PN BN29
J 2
(690 1260);
DISPLAY 0.680851 (690 1260);
PAINT MONO (690 1260);
FORCEPROP 0 LASTPIN (3100 1750) $PN BH69
J 0
(3110 1760);
DISPLAY 0.680851 (3110 1760);
PAINT MONO (3110 1760);
FORCEPROP 0 LASTPIN (700 1200) $PN BP30
J 2
(690 1210);
DISPLAY 0.680851 (690 1210);
PAINT MONO (690 1210);
FORCEPROP 0 LASTPIN (3100 1700) $PN BC68
J 0
(3110 1710);
DISPLAY 0.680851 (3110 1710);
PAINT MONO (3110 1710);
FORCEPROP 0 LASTPIN (3100 1650) $PN BG68
J 0
(3110 1660);
DISPLAY 0.680851 (3110 1660);
PAINT MONO (3110 1660);
FORCEPROP 0 LASTPIN (3100 1600) $PN BD67
J 0
(3110 1610);
DISPLAY 0.680851 (3110 1610);
PAINT MONO (3110 1610);
FORCEPROP 0 LASTPIN (3100 1550) $PN BK69
J 0
(3110 1560);
DISPLAY 0.680851 (3110 1560);
PAINT MONO (3110 1560);
FORCEPROP 0 LASTPIN (3100 1500) $PN BM69
J 0
(3110 1510);
DISPLAY 0.680851 (3110 1510);
PAINT MONO (3110 1510);
FORCEPROP 0 LASTPIN (3100 1450) $PN BN68
J 0
(3110 1460);
DISPLAY 0.680851 (3110 1460);
PAINT MONO (3110 1460);
FORCEPROP 0 LASTPIN (3100 1400) $PN BG66
J 0
(3110 1410);
DISPLAY 0.680851 (3110 1410);
PAINT MONO (3110 1410);
FORCEPROP 0 LASTPIN (3100 1350) $PN BJ66
J 0
(3110 1360);
DISPLAY 0.680851 (3110 1360);
PAINT MONO (3110 1360);
FORCEPROP 0 LASTPIN (3100 1300) $PN BL66
J 0
(3110 1310);
DISPLAY 0.680851 (3110 1310);
PAINT MONO (3110 1310);
FORCEPROP 0 LASTPIN (3100 1250) $PN BM67
J 0
(3110 1260);
DISPLAY 0.680851 (3110 1260);
PAINT MONO (3110 1260);
FORCEPROP 0 LASTPIN (3100 1200) $PN BN66
J 0
(3110 1210);
DISPLAY 0.680851 (3110 1210);
PAINT MONO (3110 1210);
FORCEPROP 0 LASTPIN (700 2250) $PN BA23
J 2
(690 2260);
DISPLAY 0.680851 (690 2260);
PAINT MONO (690 2260);
FORCEPROP 0 LASTPIN (700 2200) $PN CW19
J 2
(690 2210);
DISPLAY 0.680851 (690 2210);
PAINT MONO (690 2210);
FORCEPROP 0 LASTPIN (700 2150) $PN BB65
J 2
(690 2160);
DISPLAY 0.680851 (690 2160);
PAINT MONO (690 2160);
FORCEPROP 0 LASTPIN (700 2100) $PN CK71
J 2
(690 2110);
DISPLAY 0.680851 (690 2110);
PAINT MONO (690 2110);
FORCEPROP 0 LASTPIN (700 3250) $PN AN17
J 2
(690 3260);
DISPLAY 0.680851 (690 3260);
PAINT MONO (690 3260);
FORCEPROP 0 LASTPIN (700 3200) $PN AR17
J 2
(690 3210);
DISPLAY 0.680851 (690 3210);
PAINT MONO (690 3210);
FORCEPROP 0 LASTPIN (700 2800) $PN AT67
J 2
(690 2810);
DISPLAY 0.680851 (690 2810);
PAINT MONO (690 2810);
FORCEPROP 0 LASTPIN (3100 2400) $PN AU66
J 0
(3110 2410);
DISPLAY 0.680851 (3110 2410);
PAINT MONO (3110 2410);
FORCEPROP 0 LASTPIN (700 2850) $PN AU68
J 2
(690 2860);
DISPLAY 0.680851 (690 2860);
PAINT MONO (690 2860);
FORCEPROP 0 LASTPIN (3100 2450) $PN AV67
J 0
(3110 2460);
DISPLAY 0.680851 (3110 2460);
PAINT MONO (3110 2460);
FORCEPROP 0 LASTPIN (3100 3200) $PN BL21
J 0
(3110 3210);
DISPLAY 0.680851 (3110 3210);
PAINT MONO (3110 3210);
FORCEPROP 0 LASTPIN (3100 3250) $PN BN21
J 0
(3110 3260);
DISPLAY 0.680851 (3110 3260);
PAINT MONO (3110 3260);
FORCEPROP 0 LASTPIN (700 3050) $PN BV22
J 2
(690 3060);
DISPLAY 0.680851 (690 3060);
PAINT MONO (690 3060);
FORCEPROP 0 LASTPIN (700 2400) $PN BW21
J 2
(690 2410);
DISPLAY 0.680851 (690 2410);
PAINT MONO (690 2410);
FORCEPROP 0 LASTPIN (3100 2800) $PN BW23
J 0
(3110 2810);
DISPLAY 0.680851 (3110 2810);
PAINT MONO (3110 2810);
FORCEPROP 0 LASTPIN (700 2450) $PN CA21
J 2
(690 2460);
DISPLAY 0.680851 (690 2460);
PAINT MONO (690 2460);
FORCEPROP 0 LASTPIN (700 3000) $PN CA23
J 2
(690 3010);
DISPLAY 0.680851 (690 3010);
PAINT MONO (690 3010);
FORCEPROP 0 LASTPIN (3100 3000) $PN CC21
J 0
(3110 3010);
DISPLAY 0.680851 (3110 3010);
PAINT MONO (3110 3010);
FORCEPROP 0 LASTPIN (3100 2850) $PN CC23
J 0
(3110 2860);
DISPLAY 0.680851 (3110 2860);
PAINT MONO (3110 2860);
FORCEPROP 0 LASTPIN (3100 3050) $PN CE21
J 0
(3110 3060);
DISPLAY 0.680851 (3110 3060);
PAINT MONO (3110 3060);
FORCEPROP 0 LASTPIN (3100 2650) $PN CL68
J 0
(3110 2660);
DISPLAY 0.680851 (3110 2660);
PAINT MONO (3110 2660);
FORCEPROP 0 LASTPIN (3100 2600) $PN CM69
J 0
(3110 2610);
DISPLAY 0.680851 (3110 2610);
PAINT MONO (3110 2610);
FORCEPROP 0 LASTPIN (700 2650) $PN CP69
J 2
(690 2660);
DISPLAY 0.680851 (690 2660);
PAINT MONO (690 2660);
FORCEPROP 0 LASTPIN (700 2600) $PN CR68
J 2
(690 2610);
DISPLAY 0.680851 (690 2610);
PAINT MONO (690 2610);
FORCEPROP 2 LAST CDS_LIB pure_quanta
J 0
(1900 2175);
DISPLAY INVISIBLE (1900 2175);
FORCEPROP 1 LAST NEEDS_NO_SIZE TRUE
J 0
(1900 2175);
DISPLAY 0.723404 (1900 2175);
PAINT GREEN (1900 2175);
DISPLAY INVISIBLE (1900 2175);
FORCEPROP 1 LAST CDS_LMAN_SYM_OUTLINE -1050,1250,1050,-1200
J 0
(1900 2175);
DISPLAY 0.468085 (1900 2175);
PAINT GREEN (1900 2175);
DISPLAY INVISIBLE (1900 2175);
FORCEPROP 2 LAST CDS_LOCATION U1
J 0
(850 3750);
DISPLAY 1.021277 (850 3750);
DISPLAY INVISIBLE (850 3750);
FORCEPROP 0 LAST $SEC 7
J 0
(850 3750);
DISPLAY 0.680851 (850 3750);
PAINT MONO (850 3750);
DISPLAY INVISIBLE (850 3750);
FORCEPROP 2 LAST CDS_SEC 7
J 0
(850 3750);
DISPLAY 1.021277 (850 3750);
DISPLAY INVISIBLE (850 3750);
FORCEPROP 1 LAST PATH I23
J 0
(1900 2175);
DISPLAY 0.723404 (1900 2175);
PAINT GREEN (1900 2175);
DISPLAY INVISIBLE (1900 2175);
FORCEADD QUANTA_TITLE_BLOCK_C..1
(6625 -1775);
FORCEPROP 0 LAST CDS_CON_LAST_MODIFIED Fri Aug 25 14:00:33 2023
J 0
(4740 -1760);
PAINT MONO (4740 -1760);
DISPLAY INVISIBLE (4740 -1760);
FORCEPROP 1 LAST CUSTOM_TXT_CDS <CON_LAST_MODIFIED>
J 0
(4740 -1760);
DISPLAY 0.978723 (4740 -1760);
FORCEPROP 2 LAST CUSTOM_TXT_CDS <XR_PAGE_TITLE>
J 0
(-1265 3475);
DISPLAY 0.638298 (-1265 3475);
PAINT PINK (-1265 3475);
DISPLAY INVISIBLE (-1265 3475);
FORCEPROP 2 LAST CUSTOM_TXT_CDS <Q_NUMBER>
J 0
(5222 -1672);
DISPLAY 1.212766 (5222 -1672);
FORCEPROP 1 LAST CUSTOM_TXT_CDS <NAME_2>
J 0
(3450 -1725);
FORCEPROP 1 LAST CUSTOM_TXT_CDS <NAME_1>
J 0
(3450 -1600);
FORCEPROP 1 LAST CUSTOM_TXT_CDS <Q_PROJ>
J 0
(4243 -1673);
DISPLAY 1.212766 (4243 -1673);
FORCEPROP 1 LAST CUSTOM_TXT_CDS <Q_REV>
J 0
(6441 -1672);
DISPLAY 1.212766 (6441 -1672);
FORCEPROP 1 LAST CUSTOM_TXT_CDS <CON_PAGE_NUM> OF <CON_TOTAL_PAGES>
J 0
(6179 -1757);
DISPLAY 0.978723 (6179 -1757);
FORCEPROP 1 LAST Q_TITLE SPR CPU1 MISC:7 OF 30)
J 0
(-2741 -1749);
DISPLAY 1.957447 (-2741 -1749);
PAINT GREEN (-2741 -1749);
FORCEPROP 1 LAST Q_DEPT 
J 1
(2862 -1726);
DISPLAY 1.957447 (2862 -1726);
PAINT GREEN (2862 -1726);
FORCEPROP 1 LAST COMMENT_BODY TRUE
J 0
(6637 -1788);
DISPLAY 0.978723 (6637 -1788);
PAINT GREEN (6637 -1788);
DISPLAY INVISIBLE (6637 -1788);
FORCEPROP 2 LAST CDS_XR_PAGE_TITLE CR-50 : @S9S_MB_2U_LIB.S9S_MB_2U(SCH_1):PAGE50
J 0
(-1265 3475);
DISPLAY 0.638298 (-1265 3475);
PAINT PINK (-1265 3475);
DISPLAY INVISIBLE (-1265 3475);
FORCEPROP 2 LAST CDS_LIB pure_quanta
J 0
(6625 -1775);
PAINT MONO (6625 -1775);
DISPLAY INVISIBLE (6625 -1775);
FORCEPROP 1 LAST CDS_LMAN_SYM_OUTLINE -9475,6775,100,-125
J 0
(6625 -1775);
DISPLAY 0.468085 (6625 -1775);
PAINT GREEN (6625 -1775);
DISPLAY INVISIBLE (6625 -1775);
FORCEPROP 2 LAST PAGE_BORDER TRUE
J 0
(-1265 3475);
DISPLAY 0.638298 (-1265 3475);
PAINT PINK (-1265 3475);
DISPLAY INVISIBLE (-1265 3475);
WIRE 16 -1 (-975 2650)(700 2650);
FORCEPROP 2 LAST SIG_NAME NC_CPU1_UPI3_APROBE<0>
J 0
(-912 2659);
DISPLAY 0.680851 (-912 2659);
PAINT WHITE (-912 2659);
WIRE 16 -1 (-975 2600)(700 2600);
FORCEPROP 2 LAST SIG_NAME NC_CPU1_UPI3_APROBE<1>
J 0
(-912 2609);
DISPLAY 0.680851 (-912 2609);
PAINT WHITE (-912 2609);
WIRE 16 -1 (-975 2450)(700 2450);
FORCEPROP 2 LAST SIG_NAME NC_CPU1_DMI_APROBE<0>
J 0
(-912 2459);
DISPLAY 0.680851 (-912 2459);
PAINT WHITE (-912 2459);
WIRE 16 -1 (700 2400)(-975 2400);
FORCEPROP 2 LAST SIG_NAME NC_CPU1_DMI_APROBE<1>
J 0
(-912 2409);
DISPLAY 0.680851 (-912 2409);
PAINT WHITE (-912 2409);
WIRE 16 -1 (-975 1200)(700 1200);
FORCEPROP 2 LAST SIG_NAME TP_TRC_CPU1_PTI<15>
J 0
(-912 1209);
DISPLAY 0.680851 (-912 1209);
PAINT WHITE (-912 1209);
WIRE 16 -1 (-975 1250)(700 1250);
FORCEPROP 2 LAST SIG_NAME TP_TRC_CPU1_PTI<14>
J 0
(-912 1259);
DISPLAY 0.680851 (-912 1259);
PAINT WHITE (-912 1259);
WIRE 16 -1 (-975 1300)(700 1300);
FORCEPROP 2 LAST SIG_NAME TP_TRC_CPU1_PTI<13>
J 0
(-912 1309);
DISPLAY 0.680851 (-912 1309);
PAINT WHITE (-912 1309);
WIRE 16 -1 (-975 1350)(700 1350);
FORCEPROP 2 LAST SIG_NAME TP_TRC_CPU1_PTI<12>
J 0
(-912 1359);
DISPLAY 0.680851 (-912 1359);
PAINT WHITE (-912 1359);
WIRE 16 -1 (700 1400)(-975 1400);
FORCEPROP 2 LAST SIG_NAME TP_TRC_CPU1_PTI<11>
J 0
(-912 1409);
DISPLAY 0.680851 (-912 1409);
PAINT WHITE (-912 1409);
WIRE 16 -1 (-975 1450)(700 1450);
FORCEPROP 2 LAST SIG_NAME TP_TRC_CPU1_PTI<10>
J 0
(-912 1459);
DISPLAY 0.680851 (-912 1459);
PAINT WHITE (-912 1459);
WIRE 16 -1 (700 1500)(-975 1500);
FORCEPROP 2 LAST SIG_NAME TP_TRC_CPU1_PTI<9>
J 0
(-912 1509);
DISPLAY 0.680851 (-912 1509);
PAINT WHITE (-912 1509);
WIRE 16 -1 (-975 1550)(700 1550);
FORCEPROP 2 LAST SIG_NAME TP_TRC_CPU1_PTI<8>
J 0
(-912 1559);
DISPLAY 0.680851 (-912 1559);
PAINT WHITE (-912 1559);
WIRE 16 -1 (-975 1600)(700 1600);
FORCEPROP 2 LAST SIG_NAME TP_TRC_CPU1_PTI<7>
J 0
(-912 1609);
DISPLAY 0.680851 (-912 1609);
PAINT WHITE (-912 1609);
WIRE 16 -1 (-975 1650)(700 1650);
FORCEPROP 2 LAST SIG_NAME TP_TRC_CPU1_PTI<6>
J 0
(-912 1659);
DISPLAY 0.680851 (-912 1659);
PAINT WHITE (-912 1659);
WIRE 16 -1 (-975 1700)(700 1700);
FORCEPROP 2 LAST SIG_NAME TP_TRC_CPU1_PTI<5>
J 0
(-912 1709);
DISPLAY 0.680851 (-912 1709);
PAINT WHITE (-912 1709);
WIRE 16 -1 (-975 1750)(700 1750);
FORCEPROP 2 LAST SIG_NAME TP_TRC_CPU1_PTI<4>
J 0
(-912 1759);
DISPLAY 0.680851 (-912 1759);
PAINT WHITE (-912 1759);
WIRE 16 -1 (700 1800)(-975 1800);
FORCEPROP 2 LAST SIG_NAME TP_TRC_CPU1_PTI<3>
J 0
(-912 1809);
DISPLAY 0.680851 (-912 1809);
PAINT WHITE (-912 1809);
WIRE 16 -1 (-975 1850)(700 1850);
FORCEPROP 2 LAST SIG_NAME TP_TRC_CPU1_PTI<2>
J 0
(-912 1859);
DISPLAY 0.680851 (-912 1859);
PAINT WHITE (-912 1859);
WIRE 16 -1 (-975 1900)(700 1900);
FORCEPROP 2 LAST SIG_NAME TP_TRC_CPU1_PTI<1>
J 0
(-912 1909);
DISPLAY 0.680851 (-912 1909);
PAINT WHITE (-912 1909);
WIRE 16 -1 (700 1950)(-975 1950);
FORCEPROP 2 LAST SIG_NAME TP_TRC_CPU1_PTI<0>
J 0
(-912 1959);
DISPLAY 0.680851 (-912 1959);
PAINT WHITE (-912 1959);
WIRE 16 -1 (-975 1150)(700 1150);
FORCEPROP 2 LAST SIG_NAME TP_TRC_CPU1_PTI0_CLK
J 0
(-912 1159);
DISPLAY 0.680851 (-912 1159);
PAINT WHITE (-912 1159);
WIRE 16 -1 (700 1100)(-975 1100);
FORCEPROP 2 LAST SIG_NAME TP_TRC_CPU1_PTI1_CLK
J 0
(-912 1109);
DISPLAY 0.680851 (-912 1109);
PAINT WHITE (-912 1109);
WIRE 16 -1 (4775 1200)(3100 1200);
FORCEPROP 2 LAST SIG_NAME TP_TRC_CPU1_PTI<31>
J 0
(3359 1209);
DISPLAY 0.680851 (3359 1209);
PAINT WHITE (3359 1209);
WIRE 16 -1 (4775 1250)(3100 1250);
FORCEPROP 2 LAST SIG_NAME TP_TRC_CPU1_PTI<30>
J 0
(3359 1259);
DISPLAY 0.680851 (3359 1259);
PAINT WHITE (3359 1259);
WIRE 16 -1 (4775 1300)(3100 1300);
FORCEPROP 2 LAST SIG_NAME TP_TRC_CPU1_PTI<29>
J 0
(3359 1309);
DISPLAY 0.680851 (3359 1309);
PAINT WHITE (3359 1309);
WIRE 16 -1 (4775 1350)(3100 1350);
FORCEPROP 2 LAST SIG_NAME TP_TRC_CPU1_PTI<28>
J 0
(3359 1359);
DISPLAY 0.680851 (3359 1359);
PAINT WHITE (3359 1359);
WIRE 16 -1 (4775 1400)(3100 1400);
FORCEPROP 2 LAST SIG_NAME TP_TRC_CPU1_PTI<27>
J 0
(3359 1409);
DISPLAY 0.680851 (3359 1409);
PAINT WHITE (3359 1409);
WIRE 16 -1 (4775 1450)(3100 1450);
FORCEPROP 2 LAST SIG_NAME TP_TRC_CPU1_PTI<26>
J 0
(3359 1459);
DISPLAY 0.680851 (3359 1459);
PAINT WHITE (3359 1459);
WIRE 16 -1 (4775 1500)(3100 1500);
FORCEPROP 2 LAST SIG_NAME TP_TRC_CPU1_PTI<25>
J 0
(3359 1509);
DISPLAY 0.680851 (3359 1509);
PAINT WHITE (3359 1509);
WIRE 16 -1 (4775 1550)(3100 1550);
FORCEPROP 2 LAST SIG_NAME TP_TRC_CPU1_PTI<24>
J 0
(3359 1559);
DISPLAY 0.680851 (3359 1559);
PAINT WHITE (3359 1559);
WIRE 16 -1 (4775 1600)(3100 1600);
FORCEPROP 2 LAST SIG_NAME TP_TRC_CPU1_PTI<23>
J 0
(3359 1609);
DISPLAY 0.680851 (3359 1609);
PAINT WHITE (3359 1609);
WIRE 16 -1 (4775 1650)(3100 1650);
FORCEPROP 2 LAST SIG_NAME TP_TRC_CPU1_PTI<22>
J 0
(3359 1659);
DISPLAY 0.680851 (3359 1659);
PAINT WHITE (3359 1659);
WIRE 16 -1 (4775 1700)(3100 1700);
FORCEPROP 2 LAST SIG_NAME TP_TRC_CPU1_PTI<21>
J 0
(3359 1709);
DISPLAY 0.680851 (3359 1709);
PAINT WHITE (3359 1709);
WIRE 16 -1 (4775 1750)(3100 1750);
FORCEPROP 2 LAST SIG_NAME TP_TRC_CPU1_PTI<20>
J 0
(3359 1759);
DISPLAY 0.680851 (3359 1759);
PAINT WHITE (3359 1759);
WIRE 16 -1 (4775 1800)(3100 1800);
FORCEPROP 2 LAST SIG_NAME TP_TRC_CPU1_PTI<19>
J 0
(3359 1809);
DISPLAY 0.680851 (3359 1809);
PAINT WHITE (3359 1809);
WIRE 16 -1 (4775 1850)(3100 1850);
FORCEPROP 2 LAST SIG_NAME TP_TRC_CPU1_PTI<18>
J 0
(3359 1859);
DISPLAY 0.680851 (3359 1859);
PAINT WHITE (3359 1859);
WIRE 16 -1 (4775 1900)(3100 1900);
FORCEPROP 2 LAST SIG_NAME TP_TRC_CPU1_PTI<17>
J 0
(3359 1909);
DISPLAY 0.680851 (3359 1909);
PAINT WHITE (3359 1909);
WIRE 16 -1 (4775 1950)(3100 1950);
FORCEPROP 2 LAST SIG_NAME TP_TRC_CPU1_PTI<16>
J 0
(3359 1959);
DISPLAY 0.680851 (3359 1959);
PAINT WHITE (3359 1959);
WIRE 16 -1 (4775 1150)(3100 1150);
FORCEPROP 2 LAST SIG_NAME TP_TRC_CPU1_PTI2_CLK
J 0
(3359 1159);
DISPLAY 0.680851 (3359 1159);
PAINT WHITE (3359 1159);
WIRE 16 -1 (4775 1100)(3100 1100);
FORCEPROP 2 LAST SIG_NAME TP_TRC_CPU1_PTI3_CLK
J 0
(3359 1109);
DISPLAY 0.680851 (3359 1109);
PAINT WHITE (3359 1109);
WIRE 16 -1 (4775 2650)(3100 2650);
FORCEPROP 2 LAST SIG_NAME NC_CPU1_PE3_APROBE<0>
J 0
(3359 2659);
DISPLAY 0.680851 (3359 2659);
PAINT WHITE (3359 2659);
WIRE 16 -1 (4775 2600)(3100 2600);
FORCEPROP 2 LAST SIG_NAME NC_CPU1_PE3_APROBE<1>
J 0
(3359 2609);
DISPLAY 0.680851 (3359 2609);
PAINT WHITE (3359 2609);
WIRE 16 -1 (4775 2400)(3100 2400);
FORCEPROP 2 LAST SIG_NAME NC_CPU1_PE4_APROBE<1>
J 0
(3359 2409);
DISPLAY 0.680851 (3359 2409);
PAINT WHITE (3359 2409);
WIRE 16 -1 (700 2850)(-975 2850);
FORCEPROP 2 LAST SIG_NAME NC_CPU1_UPI2_APROBE<0>
J 0
(-912 2859);
DISPLAY 0.680851 (-912 2859);
PAINT WHITE (-912 2859);
WIRE 16 -1 (700 3250)(-975 3250);
FORCEPROP 2 LAST SIG_NAME NC_CPU1_UPI0_APROBE<0>
J 0
(-912 3259);
DISPLAY 0.680851 (-912 3259);
PAINT WHITE (-912 3259);
WIRE 16 -1 (4775 2450)(3100 2450);
FORCEPROP 2 LAST SIG_NAME NC_CPU1_PE4_APROBE<0>
J 0
(3359 2459);
DISPLAY 0.680851 (3359 2459);
PAINT WHITE (3359 2459);
WIRE 16 -1 (700 3200)(-975 3200);
FORCEPROP 2 LAST SIG_NAME NC_CPU1_UPI0_APROBE<1>
J 0
(-912 3209);
DISPLAY 0.680851 (-912 3209);
PAINT WHITE (-912 3209);
WIRE 16 -1 (-975 2800)(700 2800);
FORCEPROP 2 LAST SIG_NAME NC_CPU1_UPI2_APROBE<1>
J 0
(-912 2809);
DISPLAY 0.680851 (-912 2809);
PAINT WHITE (-912 2809);
WIRE 16 -1 (4775 3200)(3100 3200);
FORCEPROP 2 LAST SIG_NAME NC_CPU1_PE0_APROBE<1>
J 0
(3359 3209);
DISPLAY 0.680851 (3359 3209);
PAINT WHITE (3359 3209);
WIRE 16 -1 (4775 3250)(3100 3250);
FORCEPROP 2 LAST SIG_NAME NC_CPU1_PE0_APROBE<0>
J 0
(3359 3259);
DISPLAY 0.680851 (3359 3259);
PAINT WHITE (3359 3259);
WIRE 16 -1 (-975 3050)(700 3050);
FORCEPROP 2 LAST SIG_NAME NC_CPU1_UPI1_APROBE<0>
J 0
(-912 3059);
DISPLAY 0.680851 (-912 3059);
PAINT WHITE (-912 3059);
WIRE 16 -1 (4775 2800)(3100 2800);
FORCEPROP 2 LAST SIG_NAME NC_CPU1_PE2_APROBE<1>
J 0
(3359 2809);
DISPLAY 0.680851 (3359 2809);
PAINT WHITE (3359 2809);
WIRE 16 -1 (700 3000)(-975 3000);
FORCEPROP 2 LAST SIG_NAME NC_CPU1_UPI1_APROBE<1>
J 0
(-912 3009);
DISPLAY 0.680851 (-912 3009);
PAINT WHITE (-912 3009);
WIRE 16 -1 (4775 3000)(3100 3000);
FORCEPROP 2 LAST SIG_NAME NC_CPU1_PE1_APROBE<1>
J 0
(3359 3009);
DISPLAY 0.680851 (3359 3009);
PAINT WHITE (3359 3009);
WIRE 16 -1 (4775 2850)(3100 2850);
FORCEPROP 2 LAST SIG_NAME NC_CPU1_PE2_APROBE<0>
J 0
(3359 2859);
DISPLAY 0.680851 (3359 2859);
PAINT WHITE (3359 2859);
WIRE 16 -1 (4775 3050)(3100 3050);
FORCEPROP 2 LAST SIG_NAME NC_CPU1_PE1_APROBE<0>
J 0
(3359 3059);
DISPLAY 0.680851 (3359 3059);
PAINT WHITE (3359 3059);
WIRE 16 -1 (700 2250)(-975 2250);
FORCEPROP 2 LAST SIG_NAME PU_CPU1_UPI0_AC_COUPLING
J 0
(-912 2259);
DISPLAY 0.680851 (-912 2259);
PAINT WHITE (-912 2259);
WIRE 16 -1 (-975 2200)(700 2200);
FORCEPROP 2 LAST SIG_NAME PU_CPU1_UPI1_AC_COUPLING
J 0
(-912 2209);
DISPLAY 0.680851 (-912 2209);
PAINT WHITE (-912 2209);
WIRE 16 -1 (-975 2150)(700 2150);
FORCEPROP 2 LAST SIG_NAME PU_CPU1_UPI2_AC_COUPLING
J 0
(-912 2159);
DISPLAY 0.680851 (-912 2159);
PAINT WHITE (-912 2159);
WIRE 16 -1 (700 2100)(-975 2100);
FORCEPROP 2 LAST SIG_NAME PU_CPU1_UPI3_AC_COUPLING
J 0
(-912 2109);
DISPLAY 0.680851 (-912 2109);
PAINT WHITE (-912 2109);
QUIT
